(kicad_pcb
	(version 20260206)
	(generator "pcbnew")
	(generator_version "10.0")
	(general
		(thickness 1.6)
		(legacy_teardrops no)
	)
	(paper "A4")
	(title_block
		(title "12092022_DA0F0TMDCD0_F0T_Management_Board_D_brd_V3_OCP.brd")
		(comment 1 "Grand Teton / footprints 739-744 of 1440")
	)
	(layers
		(0 "F.Cu" signal "TOP")
		(4 "In1.Cu" signal "GND")
		(6 "In2.Cu" signal "IN1")
		(8 "In3.Cu" signal "GND1")
		(10 "In4.Cu" signal "IN2")
		(12 "In5.Cu" signal "VCC")
		(14 "In6.Cu" signal "VCC1")
		(16 "In7.Cu" signal "IN3")
		(18 "In8.Cu" signal "GND2")
		(20 "In9.Cu" signal "IN4")
		(22 "In10.Cu" signal "GND3")
		(2 "B.Cu" signal "BOTTOM")
		(9 "F.Adhes" user "F.Adhesive")
		(11 "B.Adhes" user "B.Adhesive")
		(13 "F.Paste" user "Package Geometry/Pastemask Top")
		(15 "B.Paste" user "Package Geometry/Pastemask Bottom")
		(5 "F.SilkS" user "Ref Des/Silkscreen Top")
		(7 "B.SilkS" user "Ref Des/Silkscreen Bottom")
		(1 "F.Mask" user "Board Geometry/Soldermask Top")
		(3 "B.Mask" user "Board Geometry/Soldermask Bottom")
		(17 "Dwgs.User" user "User.Drawings")
		(19 "Cmts.User" user "User.Comments")
		(21 "Eco1.User" user "User.Eco1")
		(23 "Eco2.User" user "User.Eco2")
		(25 "Edge.Cuts" user "Board Geometry/Outline")
		(27 "Margin" user)
		(31 "F.CrtYd" user "Package Geometry/Place Bound Top")
		(29 "B.CrtYd" user "Package Geometry/Place Bound Bottom")
		(35 "F.Fab" user "Ref Des/Assembly Top")
		(33 "B.Fab" user "Ref Des/Assembly Bottom")
	)
	(footprint ""
		(layer "B.Cu")
		(at 57.531 -34.671 90)
		(property "Reference" "R147"
			(at 0 0 90)
			(layer "B.SilkS")
			(hide yes)
			(effects
				(font
					(size 1.27 1.27)
				)
				(justify mirror)
			)
		)
		(property "Value" ""
			(at 0 0 90)
			(layer "B.Fab")
			(effects
				(font
					(size 1.27 1.27)
				)
				(justify mirror)
			)
		)
		(duplicate_pad_numbers_are_jumpers no)
		(fp_line
			(start 0.7874 -0.4064)
			(end -0.7874 -0.4064)
			(stroke
				(width 0.1524)
				(type default)
			)
			(layer "B.SilkS")
		)
		(fp_line
			(start -0.7874 -0.4064)
			(end -0.7874 0.4064)
			(stroke
				(width 0.1524)
				(type default)
			)
			(layer "B.SilkS")
		)
		(fp_line
			(start 0.7874 0.4064)
			(end 0.7874 -0.4064)
			(stroke
				(width 0.1524)
				(type default)
			)
			(layer "B.SilkS")
		)
		(fp_line
			(start -0.7874 0.4064)
			(end 0.7874 0.4064)
			(stroke
				(width 0.1524)
				(type default)
			)
			(layer "B.SilkS")
		)
		(fp_line
			(start 0.67945 -0.305054)
			(end 0.12065 -0.305054)
			(stroke
				(width 0.1)
				(type default)
			)
			(layer "B.Fab")
		)
		(fp_line
			(start 0.12065 -0.305054)
			(end 0.12065 -0.2794)
			(stroke
				(width 0.1)
				(type default)
			)
			(layer "B.Fab")
		)
		(fp_line
			(start -0.12065 -0.3048)
			(end -0.67945 -0.3048)
			(stroke
				(width 0.1)
				(type default)
			)
			(layer "B.Fab")
		)
		(fp_line
			(start -0.67945 -0.3048)
			(end -0.67945 0.3048)
			(stroke
				(width 0.1)
				(type default)
			)
			(layer "B.Fab")
		)
		(fp_line
			(start 0.12065 -0.2794)
			(end -0.12065 -0.2794)
			(stroke
				(width 0.1)
				(type default)
			)
			(layer "B.Fab")
		)
		(fp_line
			(start -0.12065 -0.2794)
			(end -0.12065 -0.3048)
			(stroke
				(width 0.1)
				(type default)
			)
			(layer "B.Fab")
		)
		(fp_line
			(start 0.12065 0.2794)
			(end 0.12065 0.3048)
			(stroke
				(width 0.1)
				(type default)
			)
			(layer "B.Fab")
		)
		(fp_line
			(start -0.120396 0.2794)
			(end 0.12065 0.2794)
			(stroke
				(width 0.1)
				(type default)
			)
			(layer "B.Fab")
		)
		(fp_line
			(start 0.67945 0.3048)
			(end 0.67945 -0.305054)
			(stroke
				(width 0.1)
				(type default)
			)
			(layer "B.Fab")
		)
		(fp_line
			(start 0.12065 0.3048)
			(end 0.67945 0.3048)
			(stroke
				(width 0.1)
				(type default)
			)
			(layer "B.Fab")
		)
		(fp_line
			(start -0.120396 0.3048)
			(end -0.120396 0.2794)
			(stroke
				(width 0.1)
				(type default)
			)
			(layer "B.Fab")
		)
		(fp_line
			(start -0.67945 0.3048)
			(end -0.120396 0.3048)
			(stroke
				(width 0.1)
				(type default)
			)
			(layer "B.Fab")
		)
		(pad "1" smd circle
			(at 0.40005 0 270)
			(size 0 0)
			(layers "B.Cu" "B.Mask" "B.Paste")
			(net "SMB_BMC_MM8_R_SDA")
		)
		(pad "2" smd circle
			(at -0.40005 0 270)
			(size 0 0)
			(layers "B.Cu" "B.Mask" "B.Paste")
			(net "SMB_BMC_MM8_SDA")
		)
	)
	(footprint ""
		(layer "B.Cu")
		(at 20.193 -19.304 180)
		(property "Reference" "R52"
			(at 0 0 0)
			(layer "B.SilkS")
			(hide yes)
			(effects
				(font
					(size 1.27 1.27)
				)
				(justify mirror)
			)
		)
		(property "Value" ""
			(at 0 0 0)
			(layer "B.Fab")
			(effects
				(font
					(size 1.27 1.27)
				)
				(justify mirror)
			)
		)
		(duplicate_pad_numbers_are_jumpers no)
		(fp_line
			(start 0.7874 0.4064)
			(end 0.7874 -0.4064)
			(stroke
				(width 0.1524)
				(type default)
			)
			(layer "B.SilkS")
		)
		(fp_line
			(start 0.7874 -0.4064)
			(end -0.7874 -0.4064)
			(stroke
				(width 0.1524)
				(type default)
			)
			(layer "B.SilkS")
		)
		(fp_line
			(start -0.7874 0.4064)
			(end 0.7874 0.4064)
			(stroke
				(width 0.1524)
				(type default)
			)
			(layer "B.SilkS")
		)
		(fp_line
			(start -0.7874 -0.4064)
			(end -0.7874 0.4064)
			(stroke
				(width 0.1524)
				(type default)
			)
			(layer "B.SilkS")
		)
		(fp_line
			(start 0.67945 0.3048)
			(end 0.67945 -0.305054)
			(stroke
				(width 0.1)
				(type default)
			)
			(layer "B.Fab")
		)
		(fp_line
			(start 0.67945 -0.305054)
			(end 0.12065 -0.305054)
			(stroke
				(width 0.1)
				(type default)
			)
			(layer "B.Fab")
		)
		(fp_line
			(start 0.12065 0.3048)
			(end 0.67945 0.3048)
			(stroke
				(width 0.1)
				(type default)
			)
			(layer "B.Fab")
		)
		(fp_line
			(start 0.12065 0.2794)
			(end 0.12065 0.3048)
			(stroke
				(width 0.1)
				(type default)
			)
			(layer "B.Fab")
		)
		(fp_line
			(start 0.12065 -0.2794)
			(end -0.12065 -0.2794)
			(stroke
				(width 0.1)
				(type default)
			)
			(layer "B.Fab")
		)
		(fp_line
			(start 0.12065 -0.305054)
			(end 0.12065 -0.2794)
			(stroke
				(width 0.1)
				(type default)
			)
			(layer "B.Fab")
		)
		(fp_line
			(start -0.120396 0.3048)
			(end -0.120396 0.2794)
			(stroke
				(width 0.1)
				(type default)
			)
			(layer "B.Fab")
		)
		(fp_line
			(start -0.120396 0.2794)
			(end 0.12065 0.2794)
			(stroke
				(width 0.1)
				(type default)
			)
			(layer "B.Fab")
		)
		(fp_line
			(start -0.12065 -0.2794)
			(end -0.12065 -0.3048)
			(stroke
				(width 0.1)
				(type default)
			)
			(layer "B.Fab")
		)
		(fp_line
			(start -0.12065 -0.3048)
			(end -0.67945 -0.3048)
			(stroke
				(width 0.1)
				(type default)
			)
			(layer "B.Fab")
		)
		(fp_line
			(start -0.67945 0.3048)
			(end -0.120396 0.3048)
			(stroke
				(width 0.1)
				(type default)
			)
			(layer "B.Fab")
		)
		(fp_line
			(start -0.67945 -0.3048)
			(end -0.67945 0.3048)
			(stroke
				(width 0.1)
				(type default)
			)
			(layer "B.Fab")
		)
		(pad "1" smd circle
			(at 0.40005 0)
			(size 0 0)
			(layers "B.Cu" "B.Mask" "B.Paste")
			(net "P3V3_AUX")
		)
		(pad "2" smd circle
			(at -0.40005 0)
			(size 0 0)
			(layers "B.Cu" "B.Mask" "B.Paste")
			(net "TMC75_A1")
		)
	)
	(footprint ""
		(layer "B.Cu")
		(at 45.339 -96.8248 90)
		(property "Reference" "C239"
			(at 0 0 90)
			(layer "B.SilkS")
			(hide yes)
			(effects
				(font
					(size 1.27 1.27)
				)
				(justify mirror)
			)
		)
		(property "Value" ""
			(at 0 0 90)
			(layer "B.Fab")
			(effects
				(font
					(size 1.27 1.27)
				)
				(justify mirror)
			)
		)
		(duplicate_pad_numbers_are_jumpers no)
		(fp_line
			(start 0.7874 -0.4064)
			(end -0.7874 -0.4064)
			(stroke
				(width 0.1524)
				(type default)
			)
			(layer "B.SilkS")
		)
		(fp_line
			(start -0.7874 -0.4064)
			(end -0.7874 0.4064)
			(stroke
				(width 0.1524)
				(type default)
			)
			(layer "B.SilkS")
		)
		(fp_line
			(start 0.7874 0.4064)
			(end 0.7874 -0.4064)
			(stroke
				(width 0.1524)
				(type default)
			)
			(layer "B.SilkS")
		)
		(fp_line
			(start -0.7874 0.4064)
			(end 0.7874 0.4064)
			(stroke
				(width 0.1524)
				(type default)
			)
			(layer "B.SilkS")
		)
		(fp_line
			(start 0.67945 -0.305054)
			(end 0.12065 -0.305054)
			(stroke
				(width 0.1)
				(type default)
			)
			(layer "B.Fab")
		)
		(fp_line
			(start 0.12065 -0.305054)
			(end 0.12065 -0.2794)
			(stroke
				(width 0.1)
				(type default)
			)
			(layer "B.Fab")
		)
		(fp_line
			(start -0.12065 -0.3048)
			(end -0.67945 -0.3048)
			(stroke
				(width 0.1)
				(type default)
			)
			(layer "B.Fab")
		)
		(fp_line
			(start -0.67945 -0.3048)
			(end -0.67945 0.3048)
			(stroke
				(width 0.1)
				(type default)
			)
			(layer "B.Fab")
		)
		(fp_line
			(start 0.12065 -0.2794)
			(end -0.12065 -0.2794)
			(stroke
				(width 0.1)
				(type default)
			)
			(layer "B.Fab")
		)
		(fp_line
			(start -0.12065 -0.2794)
			(end -0.12065 -0.3048)
			(stroke
				(width 0.1)
				(type default)
			)
			(layer "B.Fab")
		)
		(fp_line
			(start 0.12065 0.2794)
			(end 0.12065 0.3048)
			(stroke
				(width 0.1)
				(type default)
			)
			(layer "B.Fab")
		)
		(fp_line
			(start -0.120396 0.2794)
			(end 0.12065 0.2794)
			(stroke
				(width 0.1)
				(type default)
			)
			(layer "B.Fab")
		)
		(fp_line
			(start 0.67945 0.3048)
			(end 0.67945 -0.305054)
			(stroke
				(width 0.1)
				(type default)
			)
			(layer "B.Fab")
		)
		(fp_line
			(start 0.12065 0.3048)
			(end 0.67945 0.3048)
			(stroke
				(width 0.1)
				(type default)
			)
			(layer "B.Fab")
		)
		(fp_line
			(start -0.120396 0.3048)
			(end -0.120396 0.2794)
			(stroke
				(width 0.1)
				(type default)
			)
			(layer "B.Fab")
		)
		(fp_line
			(start -0.67945 0.3048)
			(end -0.120396 0.3048)
			(stroke
				(width 0.1)
				(type default)
			)
			(layer "B.Fab")
		)
		(pad "1" smd circle
			(at 0.40005 0 270)
			(size 0 0)
			(layers "B.Cu" "B.Mask" "B.Paste")
			(net "USB3_FPNL_TXN")
		)
		(pad "2" smd circle
			(at -0.40005 0 270)
			(size 0 0)
			(layers "B.Cu" "B.Mask" "B.Paste")
			(net "USB3_01_TXN_C")
		)
	)
	(footprint ""
		(layer "B.Cu")
		(at 22.653244 -93.606112)
		(property "Reference" "C162"
			(at 0 0 0)
			(layer "B.SilkS")
			(hide yes)
			(effects
				(font
					(size 1.27 1.27)
				)
				(justify mirror)
			)
		)
		(property "Value" ""
			(at 0 0 0)
			(layer "B.Fab")
			(effects
				(font
					(size 1.27 1.27)
				)
				(justify mirror)
			)
		)
		(duplicate_pad_numbers_are_jumpers no)
		(fp_line
			(start -0.69215 -0.2921)
			(end -0.69215 0.2921)
			(stroke
				(width 0.1524)
				(type default)
			)
			(layer "B.SilkS")
		)
		(fp_line
			(start -0.69215 0.2921)
			(end 0.69215 0.2921)
			(stroke
				(width 0.1524)
				(type default)
			)
			(layer "B.SilkS")
		)
		(fp_line
			(start 0.69215 -0.2921)
			(end -0.69215 -0.2921)
			(stroke
				(width 0.1524)
				(type default)
			)
			(layer "B.SilkS")
		)
		(fp_line
			(start 0.69215 0.2921)
			(end 0.69215 -0.2921)
			(stroke
				(width 0.1524)
				(type default)
			)
			(layer "B.SilkS")
		)
		(fp_line
			(start -0.51435 -0.2794)
			(end -0.51435 0.2794)
			(stroke
				(width 0.1)
				(type default)
			)
			(layer "B.Fab")
		)
		(fp_line
			(start -0.51435 0.2794)
			(end 0.51435 0.2794)
			(stroke
				(width 0.1)
				(type default)
			)
			(layer "B.Fab")
		)
		(fp_line
			(start 0.51435 -0.2794)
			(end -0.51435 -0.2794)
			(stroke
				(width 0.1)
				(type default)
			)
			(layer "B.Fab")
		)
		(fp_line
			(start 0.51435 0.2794)
			(end 0.51435 -0.2794)
			(stroke
				(width 0.1)
				(type default)
			)
			(layer "B.Fab")
		)
		(pad "1" smd circle
			(at 0.40005 0 180)
			(size 0 0)
			(layers "B.Cu" "B.Mask" "B.Paste")
			(net "VCCIO4")
		)
		(pad "2" smd circle
			(at -0.40005 0 180)
			(size 0 0)
			(layers "B.Cu" "B.Mask" "B.Paste")
			(net "GND")
		)
		(zone
			(layer "B.Cu")
			(hatch none 0.5)
			(connect_pads
				(clearance 0)
			)
			(min_thickness 0.25)
			(keepout
				(tracks not_allowed)
				(vias allowed)
				(pads allowed)
				(copperpour not_allowed)
				(footprints allowed)
			)
			(placement
				(enabled no)
				(sheetname "")
			)
			(fill
				(thermal_gap 0.5)
				(thermal_bridge_width 0.5)
				(island_removal_mode 0)
			)
			(polygon
				(pts
					(xy 22.843744 -93.518482) (xy 22.752304 -93.460316) (xy 22.552914 -93.460316) (xy 22.462744 -93.518482)
					(xy 22.462744 -93.693742) (xy 22.552914 -93.752162) (xy 22.752304 -93.752162) (xy 22.843744 -93.693996)
				)
			)
		)
	)
	(footprint ""
		(layer "B.Cu")
		(at 79.629 -93.726 180)
		(property "Reference" "C270"
			(at 0 0 0)
			(layer "B.SilkS")
			(hide yes)
			(effects
				(font
					(size 1.27 1.27)
				)
				(justify mirror)
			)
		)
		(property "Value" ""
			(at 0 0 0)
			(layer "B.Fab")
			(effects
				(font
					(size 1.27 1.27)
				)
				(justify mirror)
			)
		)
		(duplicate_pad_numbers_are_jumpers no)
		(fp_line
			(start 0.7874 0.4064)
			(end 0.7874 -0.4064)
			(stroke
				(width 0.1524)
				(type default)
			)
			(layer "B.SilkS")
		)
		(fp_line
			(start 0.7874 -0.4064)
			(end -0.7874 -0.4064)
			(stroke
				(width 0.1524)
				(type default)
			)
			(layer "B.SilkS")
		)
		(fp_line
			(start -0.7874 0.4064)
			(end 0.7874 0.4064)
			(stroke
				(width 0.1524)
				(type default)
			)
			(layer "B.SilkS")
		)
		(fp_line
			(start -0.7874 -0.4064)
			(end -0.7874 0.4064)
			(stroke
				(width 0.1524)
				(type default)
			)
			(layer "B.SilkS")
		)
		(fp_line
			(start 0.67945 0.3048)
			(end 0.67945 -0.305054)
			(stroke
				(width 0.1)
				(type default)
			)
			(layer "B.Fab")
		)
		(fp_line
			(start 0.67945 -0.305054)
			(end 0.12065 -0.305054)
			(stroke
				(width 0.1)
				(type default)
			)
			(layer "B.Fab")
		)
		(fp_line
			(start 0.12065 0.3048)
			(end 0.67945 0.3048)
			(stroke
				(width 0.1)
				(type default)
			)
			(layer "B.Fab")
		)
		(fp_line
			(start 0.12065 0.2794)
			(end 0.12065 0.3048)
			(stroke
				(width 0.1)
				(type default)
			)
			(layer "B.Fab")
		)
		(fp_line
			(start 0.12065 -0.2794)
			(end -0.12065 -0.2794)
			(stroke
				(width 0.1)
				(type default)
			)
			(layer "B.Fab")
		)
		(fp_line
			(start 0.12065 -0.305054)
			(end 0.12065 -0.2794)
			(stroke
				(width 0.1)
				(type default)
			)
			(layer "B.Fab")
		)
		(fp_line
			(start -0.120396 0.3048)
			(end -0.120396 0.2794)
			(stroke
				(width 0.1)
				(type default)
			)
			(layer "B.Fab")
		)
		(fp_line
			(start -0.120396 0.2794)
			(end 0.12065 0.2794)
			(stroke
				(width 0.1)
				(type default)
			)
			(layer "B.Fab")
		)
		(fp_line
			(start -0.12065 -0.2794)
			(end -0.12065 -0.3048)
			(stroke
				(width 0.1)
				(type default)
			)
			(layer "B.Fab")
		)
		(fp_line
			(start -0.12065 -0.3048)
			(end -0.67945 -0.3048)
			(stroke
				(width 0.1)
				(type default)
			)
			(layer "B.Fab")
		)
		(fp_line
			(start -0.67945 0.3048)
			(end -0.120396 0.3048)
			(stroke
				(width 0.1)
				(type default)
			)
			(layer "B.Fab")
		)
		(fp_line
			(start -0.67945 -0.3048)
			(end -0.67945 0.3048)
			(stroke
				(width 0.1)
				(type default)
			)
			(layer "B.Fab")
		)
		(pad "1" smd circle
			(at 0.40005 0)
			(size 0 0)
			(layers "B.Cu" "B.Mask" "B.Paste")
			(net "LPC_ESPI_SEL_N")
		)
		(pad "2" smd circle
			(at -0.40005 0)
			(size 0 0)
			(layers "B.Cu" "B.Mask" "B.Paste")
			(net "GND")
		)
	)
	(footprint ""
		(layer "B.Cu")
		(at 57.242202 -66.0654 -90)
		(property "Reference" "R240"
			(at 0 0 90)
			(layer "B.SilkS")
			(hide yes)
			(effects
				(font
					(size 1.27 1.27)
				)
				(justify mirror)
			)
		)
		(property "Value" ""
			(at 0 0 90)
			(layer "B.Fab")
			(effects
				(font
					(size 1.27 1.27)
				)
				(justify mirror)
			)
		)
		(duplicate_pad_numbers_are_jumpers no)
		(fp_line
			(start -0.7874 0.4064)
			(end 0.7874 0.4064)
			(stroke
				(width 0.1524)
				(type default)
			)
			(layer "B.SilkS")
		)
		(fp_line
			(start 0.7874 0.4064)
			(end 0.7874 -0.4064)
			(stroke
				(width 0.1524)
				(type default)
			)
			(layer "B.SilkS")
		)
		(fp_line
			(start -0.7874 -0.4064)
			(end -0.7874 0.4064)
			(stroke
				(width 0.1524)
				(type default)
			)
			(layer "B.SilkS")
		)
		(fp_line
			(start 0.7874 -0.4064)
			(end -0.7874 -0.4064)
			(stroke
				(width 0.1524)
				(type default)
			)
			(layer "B.SilkS")
		)
		(fp_line
			(start -0.67945 0.3048)
			(end -0.120396 0.3048)
			(stroke
				(width 0.1)
				(type default)
			)
			(layer "B.Fab")
		)
		(fp_line
			(start -0.120396 0.3048)
			(end -0.120396 0.2794)
			(stroke
				(width 0.1)
				(type default)
			)
			(layer "B.Fab")
		)
		(fp_line
			(start 0.12065 0.3048)
			(end 0.67945 0.3048)
			(stroke
				(width 0.1)
				(type default)
			)
			(layer "B.Fab")
		)
		(fp_line
			(start 0.67945 0.3048)
			(end 0.67945 -0.305054)
			(stroke
				(width 0.1)
				(type default)
			)
			(layer "B.Fab")
		)
		(fp_line
			(start -0.120396 0.2794)
			(end 0.12065 0.2794)
			(stroke
				(width 0.1)
				(type default)
			)
			(layer "B.Fab")
		)
		(fp_line
			(start 0.12065 0.2794)
			(end 0.12065 0.3048)
			(stroke
				(width 0.1)
				(type default)
			)
			(layer "B.Fab")
		)
		(fp_line
			(start -0.12065 -0.2794)
			(end -0.12065 -0.3048)
			(stroke
				(width 0.1)
				(type default)
			)
			(layer "B.Fab")
		)
		(fp_line
			(start 0.12065 -0.2794)
			(end -0.12065 -0.2794)
			(stroke
				(width 0.1)
				(type default)
			)
			(layer "B.Fab")
		)
		(fp_line
			(start -0.67945 -0.3048)
			(end -0.67945 0.3048)
			(stroke
				(width 0.1)
				(type default)
			)
			(layer "B.Fab")
		)
		(fp_line
			(start -0.12065 -0.3048)
			(end -0.67945 -0.3048)
			(stroke
				(width 0.1)
				(type default)
			)
			(layer "B.Fab")
		)
		(fp_line
			(start 0.12065 -0.305054)
			(end 0.12065 -0.2794)
			(stroke
				(width 0.1)
				(type default)
			)
			(layer "B.Fab")
		)
		(fp_line
			(start 0.67945 -0.305054)
			(end 0.12065 -0.305054)
			(stroke
				(width 0.1)
				(type default)
			)
			(layer "B.Fab")
		)
		(pad "1" smd circle
			(at 0.40005 0 90)
			(size 0 0)
			(layers "B.Cu" "B.Mask" "B.Paste")
			(net "P3V3_AUX")
		)
		(pad "2" smd circle
			(at -0.40005 0 90)
			(size 0 0)
			(layers "B.Cu" "B.Mask" "B.Paste")
			(net "PU_FWSPIWP_N")
		)
	)
)
